(kicad_pcb
	(version 20221018)
	(generator pcbnew)
	(general
    (thickness 1.7403)
  )
	(paper "A4")
	(title_block
    (title "Data Center RDIMM DDR4 Tester")
    (date "2024-09-30")
    (rev "1.2.4")
		(comment 9 "footprint 571 of 690 (J5), pads 110-214 of 404")
	)
	(layers
    (0 "F.Cu" signal)
    (1 "In1.Cu" power)
    (2 "In2.Cu" signal)
    (3 "In3.Cu" power)
    (4 "In4.Cu" power)
    (5 "In5.Cu" signal)
    (6 "In6.Cu" power)
    (7 "In7.Cu" signal)
    (8 "In8.Cu" power)
    (9 "In9.Cu" signal)
    (10 "In10.Cu" power)
    (31 "B.Cu" signal)
    (32 "B.Adhes" user "B.Adhesive")
    (33 "F.Adhes" user "F.Adhesive")
    (34 "B.Paste" user)
    (35 "F.Paste" user)
    (36 "B.SilkS" user "B.Silkscreen")
    (37 "F.SilkS" user "F.Silkscreen")
    (38 "B.Mask" user)
    (39 "F.Mask" user)
    (40 "Dwgs.User" user "User.Drawings")
    (41 "Cmts.User" user "User.Comments")
    (42 "Eco1.User" user "User.Eco1")
    (43 "Eco2.User" user "User.Eco2")
    (44 "Edge.Cuts" user)
    (45 "Margin" user)
    (46 "B.CrtYd" user "B.Courtyard")
    (47 "F.CrtYd" user "F.Courtyard")
    (48 "B.Fab" user)
    (49 "F.Fab" user)
  )
	(footprint "data-center-rdimm-ddr4-tester-footprints:FMC_SAMTEC_ASP-134486-01"
    (layer "B.Cu")
    (at 251 100 90)
    (descr "VITA 57.1 FMC – SEARAY™ HPC")
    (property "Author" "Antmicro")
    (property "License" "Apache-2.0")
    (property "MPN" "ASP-134486-01")
    (property "Manufacturer" "Samtec")
    (property "Sheetfile" "fmc_hpc.kicad_sch")
    (property "Sheetname" "FMC HPC")
    (property "ki_description" "400-pole 10-row 1.27mm Female FMC HPC Connector with gold-plated copper alloy contacts. ")
    (attr smd)
    (fp_text reference "J5" (at -28.4 4.01 270) (layer "B.SilkS")
        (effects (font (size 0.7 0.7) (thickness 0.15)) (justify left bottom mirror))
    )
    (fp_text value "ASP-134486-01" (at 0 -7.9 270) (layer "B.Fab") hide
        (effects (font (size 0.7 0.7) (thickness 0.15)) (justify left bottom mirror))
    )
    (pad "C26" smd circle (at 6.985 3.175 270) (size 0.64 0.64) (layers "B.Cu" "B.Mask")
      (net 148 "unconnected-(J5D-LA27+-PadC26)") (pinfunction "LA27+") (pintype "passive+no_connect"))
    (pad "C27" smd circle (at 8.255 3.175 270) (size 0.64 0.64) (layers "B.Cu" "B.Mask")
      (net 150 "unconnected-(J5D-LA27--PadC27)") (pinfunction "LA27-") (pintype "passive+no_connect"))
    (pad "C28" smd circle (at 9.525 3.175 270) (size 0.64 0.64) (layers "B.Cu" "B.Mask")
      (net 9 "GND") (pinfunction "GND") (pintype "passive"))
    (pad "C29" smd circle (at 10.794 3.175 270) (size 0.64 0.64) (layers "B.Cu" "B.Mask")
      (net 9 "GND") (pinfunction "GND") (pintype "passive"))
    (pad "C30" smd circle (at 12.064 3.175 270) (size 0.64 0.64) (layers "B.Cu" "B.Mask")
      (net 907 "FMC_SCL_3V3") (pinfunction "SCL") (pintype "passive"))
    (pad "C31" smd circle (at 13.335 3.175 270) (size 0.64 0.64) (layers "B.Cu" "B.Mask")
      (net 908 "FMC_SDA_3V3") (pinfunction "SDA") (pintype "passive"))
    (pad "C32" smd circle (at 14.605 3.175 270) (size 0.64 0.64) (layers "B.Cu" "B.Mask")
      (net 9 "GND") (pinfunction "GND") (pintype "passive"))
    (pad "C33" smd circle (at 15.874 3.175 270) (size 0.64 0.64) (layers "B.Cu" "B.Mask")
      (net 9 "GND") (pinfunction "GND") (pintype "passive"))
    (pad "C34" smd circle (at 17.144 3.175 270) (size 0.64 0.64) (layers "B.Cu" "B.Mask")
      (net 180 "unconnected-(J5D-GA0-PadC34)") (pinfunction "GA0") (pintype "passive+no_connect"))
    (pad "C35" smd circle (at 18.414 3.175 270) (size 0.64 0.64) (layers "B.Cu" "B.Mask")
      (net 535 "12P0V") (pinfunction "12P0V") (pintype "passive"))
    (pad "C36" smd circle (at 19.684 3.175 270) (size 0.64 0.64) (layers "B.Cu" "B.Mask")
      (net 9 "GND") (pinfunction "GND") (pintype "passive"))
    (pad "C37" smd circle (at 20.954 3.175 270) (size 0.64 0.64) (layers "B.Cu" "B.Mask")
      (net 535 "12P0V") (pinfunction "12P0V") (pintype "passive"))
    (pad "C38" smd circle (at 22.225 3.175 270) (size 0.64 0.64) (layers "B.Cu" "B.Mask")
      (net 9 "GND") (pinfunction "GND") (pintype "passive"))
    (pad "C39" smd circle (at 23.495 3.175 270) (size 0.64 0.64) (layers "B.Cu" "B.Mask")
      (net 143 "3V3_SYS") (pinfunction "3P3V") (pintype "passive"))
    (pad "C40" smd circle (at 24.765 3.175 270) (size 0.64 0.64) (layers "B.Cu" "B.Mask")
      (net 9 "GND") (pinfunction "GND") (pintype "passive"))
    (pad "D1" smd circle (at -24.766 1.905 270) (size 0.64 0.64) (layers "B.Cu" "B.Mask")
      (net 181 "Net-(J5D-PG_{C2M})") (pinfunction "PG_{C2M}") (pintype "passive"))
    (pad "D2" smd circle (at -23.496 1.905 270) (size 0.64 0.64) (layers "B.Cu" "B.Mask")
      (net 9 "GND") (pinfunction "GND") (pintype "passive"))
    (pad "D3" smd circle (at -22.226 1.905 270) (size 0.64 0.64) (layers "B.Cu" "B.Mask")
      (net 9 "GND") (pinfunction "GND") (pintype "passive"))
    (pad "D4" smd circle (at -20.955 1.905 270) (size 0.64 0.64) (layers "B.Cu" "B.Mask")
      (net 668 "/FMC HPC/GTR_REFCLK0_R_P") (pinfunction "GBTCLK0_{M2C}+") (pintype "passive"))
    (pad "D5" smd circle (at -19.685 1.905 270) (size 0.64 0.64) (layers "B.Cu" "B.Mask")
      (net 669 "/FMC HPC/GTR_REFCLK0_R_N") (pinfunction "GBTCLK0_{M2C}-") (pintype "passive"))
    (pad "D6" smd circle (at -18.415 1.905 270) (size 0.64 0.64) (layers "B.Cu" "B.Mask")
      (net 9 "GND") (pinfunction "GND") (pintype "passive"))
    (pad "D7" smd circle (at -17.145 1.905 270) (size 0.64 0.64) (layers "B.Cu" "B.Mask")
      (net 9 "GND") (pinfunction "GND") (pintype "passive"))
    (pad "D8" smd circle (at -15.875 1.905 270) (size 0.64 0.64) (layers "B.Cu" "B.Mask")
      (net 120 "~{PERST}") (pinfunction "LA01_{CC}+") (pintype "passive"))
    (pad "D9" smd circle (at -14.606 1.905 270) (size 0.64 0.64) (layers "B.Cu" "B.Mask")
      (net 182 "unconnected-(J5D-LA01_{CC}--PadD9)") (pinfunction "LA01_{CC}-") (pintype "passive+no_connect"))
    (pad "D10" smd circle (at -13.336 1.905 270) (size 0.64 0.64) (layers "B.Cu" "B.Mask")
      (net 9 "GND") (pinfunction "GND") (pintype "passive"))
    (pad "D11" smd circle (at -12.065 1.905 270) (size 0.64 0.64) (layers "B.Cu" "B.Mask")
      (net 313 "unconnected-(J5D-LA05+-PadD11)") (pinfunction "LA05+") (pintype "passive+no_connect"))
    (pad "D12" smd circle (at -10.795 1.905 270) (size 0.64 0.64) (layers "B.Cu" "B.Mask")
      (net 352 "unconnected-(J5D-LA05--PadD12)") (pinfunction "LA05-") (pintype "passive+no_connect"))
    (pad "D13" smd circle (at -9.526 1.905 270) (size 0.64 0.64) (layers "B.Cu" "B.Mask")
      (net 9 "GND") (pinfunction "GND") (pintype "passive"))
    (pad "D14" smd circle (at -8.256 1.905 270) (size 0.64 0.64) (layers "B.Cu" "B.Mask")
      (net 359 "unconnected-(J5D-LA09+-PadD14)") (pinfunction "LA09+") (pintype "passive+no_connect"))
    (pad "D15" smd circle (at -6.986 1.905 270) (size 0.64 0.64) (layers "B.Cu" "B.Mask")
      (net 361 "unconnected-(J5D-LA09--PadD15)") (pinfunction "LA09-") (pintype "passive+no_connect"))
    (pad "D16" smd circle (at -5.715 1.905 270) (size 0.64 0.64) (layers "B.Cu" "B.Mask")
      (net 9 "GND") (pinfunction "GND") (pintype "passive"))
    (pad "D17" smd circle (at -4.446 1.905 270) (size 0.64 0.64) (layers "B.Cu" "B.Mask")
      (net 362 "unconnected-(J5D-LA13+-PadD17)") (pinfunction "LA13+") (pintype "passive+no_connect"))
    (pad "D18" smd circle (at -3.175 1.905 270) (size 0.64 0.64) (layers "B.Cu" "B.Mask")
      (net 363 "unconnected-(J5D-LA13--PadD18)") (pinfunction "LA13-") (pintype "passive+no_connect"))
    (pad "D19" smd circle (at -1.905 1.905 270) (size 0.64 0.64) (layers "B.Cu" "B.Mask")
      (net 9 "GND") (pinfunction "GND") (pintype "passive"))
    (pad "D20" smd circle (at -0.635 1.905 270) (size 0.64 0.64) (layers "B.Cu" "B.Mask")
      (net 364 "unconnected-(J5D-LA17_{CC}+-PadD20)") (pinfunction "LA17_{CC}+") (pintype "passive+no_connect"))
    (pad "D21" smd circle (at 0.634 1.905 270) (size 0.64 0.64) (layers "B.Cu" "B.Mask")
      (net 365 "unconnected-(J5D-LA17_{CC}--PadD21)") (pinfunction "LA17_{CC}-") (pintype "passive+no_connect"))
    (pad "D22" smd circle (at 1.904 1.905 270) (size 0.64 0.64) (layers "B.Cu" "B.Mask")
      (net 9 "GND") (pinfunction "GND") (pintype "passive"))
    (pad "D23" smd circle (at 3.174 1.905 270) (size 0.64 0.64) (layers "B.Cu" "B.Mask")
      (net 366 "unconnected-(J5D-LA23+-PadD23)") (pinfunction "LA23+") (pintype "passive+no_connect"))
    (pad "D24" smd circle (at 4.445 1.905 270) (size 0.64 0.64) (layers "B.Cu" "B.Mask")
      (net 367 "unconnected-(J5D-LA23--PadD24)") (pinfunction "LA23-") (pintype "passive+no_connect"))
    (pad "D25" smd circle (at 5.714 1.905 270) (size 0.64 0.64) (layers "B.Cu" "B.Mask")
      (net 9 "GND") (pinfunction "GND") (pintype "passive"))
    (pad "D26" smd circle (at 6.985 1.905 270) (size 0.64 0.64) (layers "B.Cu" "B.Mask")
      (net 368 "unconnected-(J5D-LA26+-PadD26)") (pinfunction "LA26+") (pintype "passive+no_connect"))
    (pad "D27" smd circle (at 8.255 1.905 270) (size 0.64 0.64) (layers "B.Cu" "B.Mask")
      (net 369 "unconnected-(J5D-LA26--PadD27)") (pinfunction "LA26-") (pintype "passive+no_connect"))
    (pad "D28" smd circle (at 9.525 1.905 270) (size 0.64 0.64) (layers "B.Cu" "B.Mask")
      (net 9 "GND") (pinfunction "GND") (pintype "passive"))
    (pad "D29" smd circle (at 10.794 1.905 270) (size 0.64 0.64) (layers "B.Cu" "B.Mask")
      (net 126 "AUX_JTAG_TCK") (pinfunction "TCK") (pintype "passive"))
    (pad "D30" smd circle (at 12.064 1.905 270) (size 0.64 0.64) (layers "B.Cu" "B.Mask")
      (net 128 "AUX_JTAG_TDI") (pinfunction "TDI") (pintype "passive"))
    (pad "D31" smd circle (at 13.335 1.905 270) (size 0.64 0.64) (layers "B.Cu" "B.Mask")
      (net 146 "AUX_JTAG_TDO") (pinfunction "TDO") (pintype "passive"))
    (pad "D32" smd circle (at 14.605 1.905 270) (size 0.64 0.64) (layers "B.Cu" "B.Mask")
      (net 371 "unconnected-(J5D-3P3VAUX-PadD32)") (pinfunction "3P3VAUX") (pintype "passive+no_connect"))
    (pad "D33" smd circle (at 15.874 1.905 270) (size 0.64 0.64) (layers "B.Cu" "B.Mask")
      (net 131 "AUX_JTAG_TMS") (pinfunction "TMS") (pintype "passive"))
    (pad "D34" smd circle (at 17.144 1.905 270) (size 0.64 0.64) (layers "B.Cu" "B.Mask")
      (net 133 "AUX_JTAG_RST") (pinfunction "TRST_L") (pintype "passive"))
    (pad "D35" smd circle (at 18.414 1.905 270) (size 0.64 0.64) (layers "B.Cu" "B.Mask")
      (net 372 "unconnected-(J5D-GA1-PadD35)") (pinfunction "GA1") (pintype "passive+no_connect"))
    (pad "D36" smd circle (at 19.684 1.905 270) (size 0.64 0.64) (layers "B.Cu" "B.Mask")
      (net 143 "3V3_SYS") (pinfunction "3P3V") (pintype "passive"))
    (pad "D37" smd circle (at 20.954 1.905 270) (size 0.64 0.64) (layers "B.Cu" "B.Mask")
      (net 9 "GND") (pinfunction "GND") (pintype "passive"))
    (pad "D38" smd circle (at 22.225 1.905 270) (size 0.64 0.64) (layers "B.Cu" "B.Mask")
      (net 143 "3V3_SYS") (pinfunction "3P3V") (pintype "passive"))
    (pad "D39" smd circle (at 23.495 1.905 270) (size 0.64 0.64) (layers "B.Cu" "B.Mask")
      (net 9 "GND") (pinfunction "GND") (pintype "passive"))
    (pad "D40" smd circle (at 24.765 1.905 270) (size 0.64 0.64) (layers "B.Cu" "B.Mask")
      (net 143 "3V3_SYS") (pinfunction "3P3V") (pintype "passive"))
    (pad "E1" smd circle (at -24.766 0.635 270) (size 0.64 0.64) (layers "B.Cu" "B.Mask")
      (net 9 "GND") (pinfunction "GND") (pintype "passive"))
    (pad "E2" smd circle (at -23.496 0.635 270) (size 0.64 0.64) (layers "B.Cu" "B.Mask")
      (net 373 "unconnected-(J5C-HA01_{CC}+-PadE2)") (pinfunction "HA01_{CC}+") (pintype "passive+no_connect"))
    (pad "E3" smd circle (at -22.226 0.635 270) (size 0.64 0.64) (layers "B.Cu" "B.Mask")
      (net 374 "unconnected-(J5C-HA01_{CC}--PadE3)") (pinfunction "HA01_{CC}-") (pintype "passive+no_connect"))
    (pad "E4" smd circle (at -20.955 0.635 270) (size 0.64 0.64) (layers "B.Cu" "B.Mask")
      (net 9 "GND") (pinfunction "GND") (pintype "passive"))
    (pad "E5" smd circle (at -19.685 0.635 270) (size 0.64 0.64) (layers "B.Cu" "B.Mask")
      (net 9 "GND") (pinfunction "GND") (pintype "passive"))
    (pad "E6" smd circle (at -18.415 0.635 270) (size 0.64 0.64) (layers "B.Cu" "B.Mask")
      (net 375 "unconnected-(J5C-HA05+-PadE6)") (pinfunction "HA05+") (pintype "passive+no_connect"))
    (pad "E7" smd circle (at -17.145 0.635 270) (size 0.64 0.64) (layers "B.Cu" "B.Mask")
      (net 376 "unconnected-(J5C-HA05--PadE7)") (pinfunction "HA05-") (pintype "passive+no_connect"))
    (pad "E8" smd circle (at -15.875 0.635 270) (size 0.64 0.64) (layers "B.Cu" "B.Mask")
      (net 9 "GND") (pinfunction "GND") (pintype "passive"))
    (pad "E9" smd circle (at -14.606 0.635 270) (size 0.64 0.64) (layers "B.Cu" "B.Mask")
      (net 377 "unconnected-(J5C-HA09+-PadE9)") (pinfunction "HA09+") (pintype "passive+no_connect"))
    (pad "E10" smd circle (at -13.336 0.635 270) (size 0.64 0.64) (layers "B.Cu" "B.Mask")
      (net 378 "unconnected-(J5C-HA09--PadE10)") (pinfunction "HA09-") (pintype "passive+no_connect"))
    (pad "E11" smd circle (at -12.065 0.635 270) (size 0.64 0.64) (layers "B.Cu" "B.Mask")
      (net 9 "GND") (pinfunction "GND") (pintype "passive"))
    (pad "E12" smd circle (at -10.795 0.635 270) (size 0.64 0.64) (layers "B.Cu" "B.Mask")
      (net 382 "unconnected-(J5C-HA13+-PadE12)") (pinfunction "HA13+") (pintype "passive+no_connect"))
    (pad "E13" smd circle (at -9.526 0.635 270) (size 0.64 0.64) (layers "B.Cu" "B.Mask")
      (net 384 "unconnected-(J5C-HA13--PadE13)") (pinfunction "HA13-") (pintype "passive+no_connect"))
    (pad "E14" smd circle (at -8.256 0.635 270) (size 0.64 0.64) (layers "B.Cu" "B.Mask")
      (net 9 "GND") (pinfunction "GND") (pintype "passive"))
    (pad "E15" smd circle (at -6.986 0.635 270) (size 0.64 0.64) (layers "B.Cu" "B.Mask")
      (net 385 "unconnected-(J5C-HA16+-PadE15)") (pinfunction "HA16+") (pintype "passive+no_connect"))
    (pad "E16" smd circle (at -5.715 0.635 270) (size 0.64 0.64) (layers "B.Cu" "B.Mask")
      (net 386 "unconnected-(J5C-HA16--PadE16)") (pinfunction "HA16-") (pintype "passive+no_connect"))
    (pad "E17" smd circle (at -4.446 0.635 270) (size 0.64 0.64) (layers "B.Cu" "B.Mask")
      (net 9 "GND") (pinfunction "GND") (pintype "passive"))
    (pad "E18" smd circle (at -3.175 0.635 270) (size 0.64 0.64) (layers "B.Cu" "B.Mask")
      (net 387 "unconnected-(J5C-HA20+-PadE18)") (pinfunction "HA20+") (pintype "passive+no_connect"))
    (pad "E19" smd circle (at -1.905 0.635 270) (size 0.64 0.64) (layers "B.Cu" "B.Mask")
      (net 388 "unconnected-(J5C-HA20--PadE19)") (pinfunction "HA20-") (pintype "passive+no_connect"))
    (pad "E20" smd circle (at -0.635 0.635 270) (size 0.64 0.64) (layers "B.Cu" "B.Mask")
      (net 9 "GND") (pinfunction "GND") (pintype "passive"))
    (pad "E21" smd circle (at 0.634 0.635 270) (size 0.64 0.64) (layers "B.Cu" "B.Mask")
      (net 389 "unconnected-(J5C-HB03+-PadE21)") (pinfunction "HB03+") (pintype "passive+no_connect"))
    (pad "E22" smd circle (at 1.904 0.635 270) (size 0.64 0.64) (layers "B.Cu" "B.Mask")
      (net 390 "unconnected-(J5C-HB03--PadE22)") (pinfunction "HB03-") (pintype "passive+no_connect"))
    (pad "E23" smd circle (at 3.174 0.635 270) (size 0.64 0.64) (layers "B.Cu" "B.Mask")
      (net 9 "GND") (pinfunction "GND") (pintype "passive"))
    (pad "E24" smd circle (at 4.445 0.635 270) (size 0.64 0.64) (layers "B.Cu" "B.Mask")
      (net 391 "unconnected-(J5C-HB05+-PadE24)") (pinfunction "HB05+") (pintype "passive+no_connect"))
    (pad "E25" smd circle (at 5.714 0.635 270) (size 0.64 0.64) (layers "B.Cu" "B.Mask")
      (net 392 "unconnected-(J5C-HB05--PadE25)") (pinfunction "HB05-") (pintype "passive+no_connect"))
    (pad "E26" smd circle (at 6.985 0.635 270) (size 0.64 0.64) (layers "B.Cu" "B.Mask")
      (net 9 "GND") (pinfunction "GND") (pintype "passive"))
    (pad "E27" smd circle (at 8.255 0.635 270) (size 0.64 0.64) (layers "B.Cu" "B.Mask")
      (net 393 "unconnected-(J5C-HB09+-PadE27)") (pinfunction "HB09+") (pintype "passive+no_connect"))
    (pad "E28" smd circle (at 9.525 0.635 270) (size 0.64 0.64) (layers "B.Cu" "B.Mask")
      (net 394 "unconnected-(J5C-HB09--PadE28)") (pinfunction "HB09-") (pintype "passive+no_connect"))
    (pad "E29" smd circle (at 10.794 0.635 270) (size 0.64 0.64) (layers "B.Cu" "B.Mask")
      (net 9 "GND") (pinfunction "GND") (pintype "passive"))
    (pad "E30" smd circle (at 12.064 0.635 270) (size 0.64 0.64) (layers "B.Cu" "B.Mask")
      (net 395 "unconnected-(J5C-HB13+-PadE30)") (pinfunction "HB13+") (pintype "passive+no_connect"))
    (pad "E31" smd circle (at 13.335 0.635 270) (size 0.64 0.64) (layers "B.Cu" "B.Mask")
      (net 396 "unconnected-(J5C-HB13--PadE31)") (pinfunction "HB13-") (pintype "passive+no_connect"))
    (pad "E32" smd circle (at 14.605 0.635 270) (size 0.64 0.64) (layers "B.Cu" "B.Mask")
      (net 9 "GND") (pinfunction "GND") (pintype "passive"))
    (pad "E33" smd circle (at 15.874 0.635 270) (size 0.64 0.64) (layers "B.Cu" "B.Mask")
      (net 397 "unconnected-(J5C-HB19+-PadE33)") (pinfunction "HB19+") (pintype "passive+no_connect"))
    (pad "E34" smd circle (at 17.144 0.635 270) (size 0.64 0.64) (layers "B.Cu" "B.Mask")
      (net 398 "unconnected-(J5C-HB19--PadE34)") (pinfunction "HB19-") (pintype "passive+no_connect"))
    (pad "E35" smd circle (at 18.414 0.635 270) (size 0.64 0.64) (layers "B.Cu" "B.Mask")
      (net 9 "GND") (pinfunction "GND") (pintype "passive"))
    (pad "E36" smd circle (at 19.684 0.635 270) (size 0.64 0.64) (layers "B.Cu" "B.Mask")
      (net 399 "unconnected-(J5C-HB21+-PadE36)") (pinfunction "HB21+") (pintype "passive+no_connect"))
    (pad "E37" smd circle (at 20.954 0.635 270) (size 0.64 0.64) (layers "B.Cu" "B.Mask")
      (net 401 "unconnected-(J5C-HB21--PadE37)") (pinfunction "HB21-") (pintype "passive+no_connect"))
    (pad "E38" smd circle (at 22.225 0.635 270) (size 0.64 0.64) (layers "B.Cu" "B.Mask")
      (net 9 "GND") (pinfunction "GND") (pintype "passive"))
    (pad "E39" smd circle (at 23.495 0.635 270) (size 0.64 0.64) (layers "B.Cu" "B.Mask")
      (net 402 "unconnected-(J5C-VADJ-PadE39)") (pinfunction "VADJ") (pintype "passive+no_connect"))
    (pad "E40" smd circle (at 24.765 0.635 270) (size 0.64 0.64) (layers "B.Cu" "B.Mask")
      (net 9 "GND") (pinfunction "GND") (pintype "passive"))
    (pad "F1" smd circle (at -24.766 -0.634 270) (size 0.64 0.64) (layers "B.Cu" "B.Mask")
      (net 405 "Net-(J5C-PG_{M2C})") (pinfunction "PG_{M2C}") (pintype "passive"))
    (pad "F2" smd circle (at -23.496 -0.634 270) (size 0.64 0.64) (layers "B.Cu" "B.Mask")
      (net 9 "GND") (pinfunction "GND") (pintype "passive"))
    (pad "F3" smd circle (at -22.226 -0.634 270) (size 0.64 0.64) (layers "B.Cu" "B.Mask")
      (net 9 "GND") (pinfunction "GND") (pintype "passive"))
    (pad "F4" smd circle (at -20.955 -0.634 270) (size 0.64 0.64) (layers "B.Cu" "B.Mask")
      (net 413 "unconnected-(J5C-HA00_{CC}+-PadF4)") (pinfunction "HA00_{CC}+") (pintype "passive+no_connect"))
    (pad "F5" smd circle (at -19.685 -0.634 270) (size 0.64 0.64) (layers "B.Cu" "B.Mask")
      (net 414 "unconnected-(J5C-HA00_{CC}--PadF5)") (pinfunction "HA00_{CC}-") (pintype "passive+no_connect"))
    (pad "F6" smd circle (at -18.415 -0.634 270) (size 0.64 0.64) (layers "B.Cu" "B.Mask")
      (net 9 "GND") (pinfunction "GND") (pintype "passive"))
    (pad "F7" smd circle (at -17.145 -0.634 270) (size 0.64 0.64) (layers "B.Cu" "B.Mask")
      (net 415 "unconnected-(J5C-HA04+-PadF7)") (pinfunction "HA04+") (pintype "passive+no_connect"))
    (pad "F8" smd circle (at -15.875 -0.634 270) (size 0.64 0.64) (layers "B.Cu" "B.Mask")
      (net 422 "unconnected-(J5C-HA04--PadF8)") (pinfunction "HA04-") (pintype "passive+no_connect"))
    (pad "F9" smd circle (at -14.606 -0.634 270) (size 0.64 0.64) (layers "B.Cu" "B.Mask")
      (net 9 "GND") (pinfunction "GND") (pintype "passive"))
    (pad "F10" smd circle (at -13.336 -0.634 270) (size 0.64 0.64) (layers "B.Cu" "B.Mask")
      (net 423 "unconnected-(J5C-HA08+-PadF10)") (pinfunction "HA08+") (pintype "passive+no_connect"))
  )
)
